(kicad_pcb
	(version 20260206)
	(generator "pcbnew")
	(generator_version "10.0")
	(general
		(thickness 1.6)
		(legacy_teardrops no)
	)
	(paper "A4")
	(title_block
		(title "01162023_DA0F0TEBIF0_F0T_Expander_BD_F_brd_V02_OCP.brd")
		(comment 1 "Grand Teton / footprints 4712-4717 of 9728")
	)
	(layers
		(0 "F.Cu" signal "TOP")
		(4 "In1.Cu" signal "GND")
		(6 "In2.Cu" signal "VCC")
		(8 "In3.Cu" signal "VCC1")
		(10 "In4.Cu" signal "GND1")
		(12 "In5.Cu" signal "IN1")
		(14 "In6.Cu" signal "GND2")
		(16 "In7.Cu" signal "IN2")
		(18 "In8.Cu" signal "GND3")
		(20 "In9.Cu" signal "IN3")
		(22 "In10.Cu" signal "GND4")
		(24 "In11.Cu" signal "IN4")
		(26 "In12.Cu" signal "GND5")
		(28 "In13.Cu" signal "IN5")
		(30 "In14.Cu" signal "GND6")
		(32 "In15.Cu" signal "IN6")
		(34 "In16.Cu" signal "GND7")
		(2 "B.Cu" signal "BOTTOM")
		(9 "F.Adhes" user "F.Adhesive")
		(11 "B.Adhes" user "B.Adhesive")
		(13 "F.Paste" user "Package Geometry/Pastemask Top")
		(15 "B.Paste" user "Package Geometry/Pastemask Bottom")
		(5 "F.SilkS" user "Ref Des/Silkscreen Top")
		(7 "B.SilkS" user "Ref Des/Silkscreen Bottom")
		(1 "F.Mask" user "Board Geometry/Soldermask Top")
		(3 "B.Mask" user "Board Geometry/Soldermask Bottom")
		(17 "Dwgs.User" user "User.Drawings")
		(19 "Cmts.User" user "User.Comments")
		(21 "Eco1.User" user "User.Eco1")
		(23 "Eco2.User" user "User.Eco2")
		(25 "Edge.Cuts" user "Board Geometry/Outline")
		(27 "Margin" user)
		(31 "F.CrtYd" user "Package Geometry/Place Bound Top")
		(29 "B.CrtYd" user "Package Geometry/Place Bound Bottom")
		(35 "F.Fab" user "Ref Des/Assembly Top")
		(33 "B.Fab" user "Ref Des/Assembly Bottom")
	)
	(footprint ""
		(layer "F.Cu")
		(at 219.014294 -181.14518 180)
		(property "Reference" "R5497"
			(at 0 0 180)
			(layer "F.SilkS")
			(hide yes)
			(effects
				(font
					(size 1.27 1.27)
				)
			)
		)
		(property "Value" ""
			(at 0 0 180)
			(layer "F.Fab")
			(effects
				(font
					(size 1.27 1.27)
				)
			)
		)
		(duplicate_pad_numbers_are_jumpers no)
		(fp_line
			(start 0.7874 0.4064)
			(end -0.7874 0.4064)
			(stroke
				(width 0.1524)
				(type default)
			)
			(layer "F.SilkS")
		)
		(fp_line
			(start 0.7874 -0.4064)
			(end 0.7874 0.4064)
			(stroke
				(width 0.1524)
				(type default)
			)
			(layer "F.SilkS")
		)
		(fp_line
			(start -0.7874 0.4064)
			(end -0.7874 -0.4064)
			(stroke
				(width 0.1524)
				(type default)
			)
			(layer "F.SilkS")
		)
		(fp_line
			(start -0.7874 -0.4064)
			(end 0.7874 -0.4064)
			(stroke
				(width 0.1524)
				(type default)
			)
			(layer "F.SilkS")
		)
		(fp_line
			(start 0.67945 0.3048)
			(end 0.120396 0.3048)
			(stroke
				(width 0.1)
				(type default)
			)
			(layer "F.Fab")
		)
		(fp_line
			(start 0.67945 -0.3048)
			(end 0.67945 0.3048)
			(stroke
				(width 0.1)
				(type default)
			)
			(layer "F.Fab")
		)
		(fp_line
			(start 0.12065 -0.2794)
			(end 0.12065 -0.3048)
			(stroke
				(width 0.1)
				(type default)
			)
			(layer "F.Fab")
		)
		(fp_line
			(start 0.12065 -0.3048)
			(end 0.67945 -0.3048)
			(stroke
				(width 0.1)
				(type default)
			)
			(layer "F.Fab")
		)
		(fp_line
			(start 0.120396 0.3048)
			(end 0.120396 0.2794)
			(stroke
				(width 0.1)
				(type default)
			)
			(layer "F.Fab")
		)
		(fp_line
			(start 0.120396 0.2794)
			(end -0.12065 0.2794)
			(stroke
				(width 0.1)
				(type default)
			)
			(layer "F.Fab")
		)
		(fp_line
			(start -0.12065 0.3048)
			(end -0.67945 0.3048)
			(stroke
				(width 0.1)
				(type default)
			)
			(layer "F.Fab")
		)
		(fp_line
			(start -0.12065 0.2794)
			(end -0.12065 0.3048)
			(stroke
				(width 0.1)
				(type default)
			)
			(layer "F.Fab")
		)
		(fp_line
			(start -0.12065 -0.2794)
			(end 0.12065 -0.2794)
			(stroke
				(width 0.1)
				(type default)
			)
			(layer "F.Fab")
		)
		(fp_line
			(start -0.12065 -0.305054)
			(end -0.12065 -0.2794)
			(stroke
				(width 0.1)
				(type default)
			)
			(layer "F.Fab")
		)
		(fp_line
			(start -0.67945 0.3048)
			(end -0.67945 -0.305054)
			(stroke
				(width 0.1)
				(type default)
			)
			(layer "F.Fab")
		)
		(fp_line
			(start -0.67945 -0.305054)
			(end -0.12065 -0.305054)
			(stroke
				(width 0.1)
				(type default)
			)
			(layer "F.Fab")
		)
		(pad "1" smd circle
			(at -0.40005 0 180)
			(size 0 0)
			(layers "F.Cu" "F.Mask" "F.Paste")
			(net "RST_FW_BIC_PLTRST_C")
		)
		(pad "2" smd circle
			(at 0.40005 0 180)
			(size 0 0)
			(layers "F.Cu" "F.Mask" "F.Paste")
			(net "GND")
		)
	)
	(footprint ""
		(layer "F.Cu")
		(at 340.561422 -190.41745 180)
		(property "Reference" "R4243"
			(at 0 0 180)
			(layer "F.SilkS")
			(hide yes)
			(effects
				(font
					(size 1.27 1.27)
				)
			)
		)
		(property "Value" ""
			(at 0 0 180)
			(layer "F.Fab")
			(effects
				(font
					(size 1.27 1.27)
				)
			)
		)
		(duplicate_pad_numbers_are_jumpers no)
		(fp_line
			(start 0.7874 0.4064)
			(end -0.7874 0.4064)
			(stroke
				(width 0.1524)
				(type default)
			)
			(layer "F.SilkS")
		)
		(fp_line
			(start 0.7874 -0.4064)
			(end 0.7874 0.4064)
			(stroke
				(width 0.1524)
				(type default)
			)
			(layer "F.SilkS")
		)
		(fp_line
			(start -0.7874 0.4064)
			(end -0.7874 -0.4064)
			(stroke
				(width 0.1524)
				(type default)
			)
			(layer "F.SilkS")
		)
		(fp_line
			(start -0.7874 -0.4064)
			(end 0.7874 -0.4064)
			(stroke
				(width 0.1524)
				(type default)
			)
			(layer "F.SilkS")
		)
		(fp_line
			(start 0.67945 0.3048)
			(end 0.120396 0.3048)
			(stroke
				(width 0.1)
				(type default)
			)
			(layer "F.Fab")
		)
		(fp_line
			(start 0.67945 -0.3048)
			(end 0.67945 0.3048)
			(stroke
				(width 0.1)
				(type default)
			)
			(layer "F.Fab")
		)
		(fp_line
			(start 0.12065 -0.2794)
			(end 0.12065 -0.3048)
			(stroke
				(width 0.1)
				(type default)
			)
			(layer "F.Fab")
		)
		(fp_line
			(start 0.12065 -0.3048)
			(end 0.67945 -0.3048)
			(stroke
				(width 0.1)
				(type default)
			)
			(layer "F.Fab")
		)
		(fp_line
			(start 0.120396 0.3048)
			(end 0.120396 0.2794)
			(stroke
				(width 0.1)
				(type default)
			)
			(layer "F.Fab")
		)
		(fp_line
			(start 0.120396 0.2794)
			(end -0.12065 0.2794)
			(stroke
				(width 0.1)
				(type default)
			)
			(layer "F.Fab")
		)
		(fp_line
			(start -0.12065 0.3048)
			(end -0.67945 0.3048)
			(stroke
				(width 0.1)
				(type default)
			)
			(layer "F.Fab")
		)
		(fp_line
			(start -0.12065 0.2794)
			(end -0.12065 0.3048)
			(stroke
				(width 0.1)
				(type default)
			)
			(layer "F.Fab")
		)
		(fp_line
			(start -0.12065 -0.2794)
			(end 0.12065 -0.2794)
			(stroke
				(width 0.1)
				(type default)
			)
			(layer "F.Fab")
		)
		(fp_line
			(start -0.12065 -0.305054)
			(end -0.12065 -0.2794)
			(stroke
				(width 0.1)
				(type default)
			)
			(layer "F.Fab")
		)
		(fp_line
			(start -0.67945 0.3048)
			(end -0.67945 -0.305054)
			(stroke
				(width 0.1)
				(type default)
			)
			(layer "F.Fab")
		)
		(fp_line
			(start -0.67945 -0.305054)
			(end -0.12065 -0.305054)
			(stroke
				(width 0.1)
				(type default)
			)
			(layer "F.Fab")
		)
		(pad "1" smd circle
			(at -0.40005 0 180)
			(size 0 0)
			(layers "F.Cu" "F.Mask" "F.Paste")
			(net "P3V3_AUX")
		)
		(pad "2" smd circle
			(at 0.40005 0 180)
			(size 0 0)
			(layers "F.Cu" "F.Mask" "F.Paste")
			(net "RST_PLTRST_N")
		)
	)
	(footprint ""
		(layer "F.Cu")
		(at 80.53959 -159.235648 180)
		(property "Reference" "R93"
			(at 0 0 180)
			(layer "F.SilkS")
			(hide yes)
			(effects
				(font
					(size 1.27 1.27)
				)
			)
		)
		(property "Value" ""
			(at 0 0 180)
			(layer "F.Fab")
			(effects
				(font
					(size 1.27 1.27)
				)
			)
		)
		(duplicate_pad_numbers_are_jumpers no)
		(fp_line
			(start 0.7874 0.4064)
			(end -0.7874 0.4064)
			(stroke
				(width 0.1524)
				(type default)
			)
			(layer "F.SilkS")
		)
		(fp_line
			(start 0.7874 -0.4064)
			(end 0.7874 0.4064)
			(stroke
				(width 0.1524)
				(type default)
			)
			(layer "F.SilkS")
		)
		(fp_line
			(start -0.7874 0.4064)
			(end -0.7874 -0.4064)
			(stroke
				(width 0.1524)
				(type default)
			)
			(layer "F.SilkS")
		)
		(fp_line
			(start -0.7874 -0.4064)
			(end 0.7874 -0.4064)
			(stroke
				(width 0.1524)
				(type default)
			)
			(layer "F.SilkS")
		)
		(fp_line
			(start 0.67945 0.3048)
			(end 0.120396 0.3048)
			(stroke
				(width 0.1)
				(type default)
			)
			(layer "F.Fab")
		)
		(fp_line
			(start 0.67945 -0.3048)
			(end 0.67945 0.3048)
			(stroke
				(width 0.1)
				(type default)
			)
			(layer "F.Fab")
		)
		(fp_line
			(start 0.12065 -0.2794)
			(end 0.12065 -0.3048)
			(stroke
				(width 0.1)
				(type default)
			)
			(layer "F.Fab")
		)
		(fp_line
			(start 0.12065 -0.3048)
			(end 0.67945 -0.3048)
			(stroke
				(width 0.1)
				(type default)
			)
			(layer "F.Fab")
		)
		(fp_line
			(start 0.120396 0.3048)
			(end 0.120396 0.2794)
			(stroke
				(width 0.1)
				(type default)
			)
			(layer "F.Fab")
		)
		(fp_line
			(start 0.120396 0.2794)
			(end -0.12065 0.2794)
			(stroke
				(width 0.1)
				(type default)
			)
			(layer "F.Fab")
		)
		(fp_line
			(start -0.12065 0.3048)
			(end -0.67945 0.3048)
			(stroke
				(width 0.1)
				(type default)
			)
			(layer "F.Fab")
		)
		(fp_line
			(start -0.12065 0.2794)
			(end -0.12065 0.3048)
			(stroke
				(width 0.1)
				(type default)
			)
			(layer "F.Fab")
		)
		(fp_line
			(start -0.12065 -0.2794)
			(end 0.12065 -0.2794)
			(stroke
				(width 0.1)
				(type default)
			)
			(layer "F.Fab")
		)
		(fp_line
			(start -0.12065 -0.305054)
			(end -0.12065 -0.2794)
			(stroke
				(width 0.1)
				(type default)
			)
			(layer "F.Fab")
		)
		(fp_line
			(start -0.67945 0.3048)
			(end -0.67945 -0.305054)
			(stroke
				(width 0.1)
				(type default)
			)
			(layer "F.Fab")
		)
		(fp_line
			(start -0.67945 -0.305054)
			(end -0.12065 -0.305054)
			(stroke
				(width 0.1)
				(type default)
			)
			(layer "F.Fab")
		)
		(pad "1" smd circle
			(at -0.40005 0 180)
			(size 0 0)
			(layers "F.Cu" "F.Mask" "F.Paste")
			(net "PRSNT_NIC1_N")
		)
		(pad "2" smd circle
			(at 0.40005 0 180)
			(size 0 0)
			(layers "F.Cu" "F.Mask" "F.Paste")
			(net "PRSNTB3_NIC1_N")
		)
	)
	(footprint ""
		(layer "F.Cu")
		(at 374.543828 -42.84091)
		(property "Reference" "R637"
			(at 0 0 0)
			(layer "F.SilkS")
			(hide yes)
			(effects
				(font
					(size 1.27 1.27)
				)
			)
		)
		(property "Value" ""
			(at 0 0 0)
			(layer "F.Fab")
			(effects
				(font
					(size 1.27 1.27)
				)
			)
		)
		(duplicate_pad_numbers_are_jumpers no)
		(fp_line
			(start -0.7874 -0.4064)
			(end 0.7874 -0.4064)
			(stroke
				(width 0.1524)
				(type default)
			)
			(layer "F.SilkS")
		)
		(fp_line
			(start -0.7874 0.4064)
			(end -0.7874 -0.4064)
			(stroke
				(width 0.1524)
				(type default)
			)
			(layer "F.SilkS")
		)
		(fp_line
			(start 0.7874 -0.4064)
			(end 0.7874 0.4064)
			(stroke
				(width 0.1524)
				(type default)
			)
			(layer "F.SilkS")
		)
		(fp_line
			(start 0.7874 0.4064)
			(end -0.7874 0.4064)
			(stroke
				(width 0.1524)
				(type default)
			)
			(layer "F.SilkS")
		)
		(fp_line
			(start -0.67945 -0.305054)
			(end -0.12065 -0.305054)
			(stroke
				(width 0.1)
				(type default)
			)
			(layer "F.Fab")
		)
		(fp_line
			(start -0.67945 0.3048)
			(end -0.67945 -0.305054)
			(stroke
				(width 0.1)
				(type default)
			)
			(layer "F.Fab")
		)
		(fp_line
			(start -0.12065 -0.305054)
			(end -0.12065 -0.2794)
			(stroke
				(width 0.1)
				(type default)
			)
			(layer "F.Fab")
		)
		(fp_line
			(start -0.12065 -0.2794)
			(end 0.12065 -0.2794)
			(stroke
				(width 0.1)
				(type default)
			)
			(layer "F.Fab")
		)
		(fp_line
			(start -0.12065 0.2794)
			(end -0.12065 0.3048)
			(stroke
				(width 0.1)
				(type default)
			)
			(layer "F.Fab")
		)
		(fp_line
			(start -0.12065 0.3048)
			(end -0.67945 0.3048)
			(stroke
				(width 0.1)
				(type default)
			)
			(layer "F.Fab")
		)
		(fp_line
			(start 0.120396 0.2794)
			(end -0.12065 0.2794)
			(stroke
				(width 0.1)
				(type default)
			)
			(layer "F.Fab")
		)
		(fp_line
			(start 0.120396 0.3048)
			(end 0.120396 0.2794)
			(stroke
				(width 0.1)
				(type default)
			)
			(layer "F.Fab")
		)
		(fp_line
			(start 0.12065 -0.3048)
			(end 0.67945 -0.3048)
			(stroke
				(width 0.1)
				(type default)
			)
			(layer "F.Fab")
		)
		(fp_line
			(start 0.12065 -0.2794)
			(end 0.12065 -0.3048)
			(stroke
				(width 0.1)
				(type default)
			)
			(layer "F.Fab")
		)
		(fp_line
			(start 0.67945 -0.3048)
			(end 0.67945 0.3048)
			(stroke
				(width 0.1)
				(type default)
			)
			(layer "F.Fab")
		)
		(fp_line
			(start 0.67945 0.3048)
			(end 0.120396 0.3048)
			(stroke
				(width 0.1)
				(type default)
			)
			(layer "F.Fab")
		)
		(pad "1" smd circle
			(at -0.40005 0)
			(size 0 0)
			(layers "F.Cu" "F.Mask" "F.Paste")
			(net "SSD12_ADC_A1")
		)
		(pad "2" smd circle
			(at 0.40005 0)
			(size 0 0)
			(layers "F.Cu" "F.Mask" "F.Paste")
			(net "P3V3_AUX")
		)
	)
	(footprint ""
		(layer "F.Cu")
		(at 113.561114 -259.782564 180)
		(property "Reference" "PR92"
			(at 0 0 180)
			(layer "F.SilkS")
			(hide yes)
			(effects
				(font
					(size 1.27 1.27)
				)
			)
		)
		(property "Value" ""
			(at 0 0 180)
			(layer "F.Fab")
			(effects
				(font
					(size 1.27 1.27)
				)
			)
		)
		(duplicate_pad_numbers_are_jumpers no)
		(fp_line
			(start 0.7874 0.4064)
			(end -0.7874 0.4064)
			(stroke
				(width 0.1524)
				(type default)
			)
			(layer "F.SilkS")
		)
		(fp_line
			(start 0.7874 -0.4064)
			(end 0.7874 0.4064)
			(stroke
				(width 0.1524)
				(type default)
			)
			(layer "F.SilkS")
		)
		(fp_line
			(start -0.7874 0.4064)
			(end -0.7874 -0.4064)
			(stroke
				(width 0.1524)
				(type default)
			)
			(layer "F.SilkS")
		)
		(fp_line
			(start -0.7874 -0.4064)
			(end 0.7874 -0.4064)
			(stroke
				(width 0.1524)
				(type default)
			)
			(layer "F.SilkS")
		)
		(fp_line
			(start 0.67945 0.3048)
			(end 0.120396 0.3048)
			(stroke
				(width 0.1)
				(type default)
			)
			(layer "F.Fab")
		)
		(fp_line
			(start 0.67945 -0.3048)
			(end 0.67945 0.3048)
			(stroke
				(width 0.1)
				(type default)
			)
			(layer "F.Fab")
		)
		(fp_line
			(start 0.12065 -0.2794)
			(end 0.12065 -0.3048)
			(stroke
				(width 0.1)
				(type default)
			)
			(layer "F.Fab")
		)
		(fp_line
			(start 0.12065 -0.3048)
			(end 0.67945 -0.3048)
			(stroke
				(width 0.1)
				(type default)
			)
			(layer "F.Fab")
		)
		(fp_line
			(start 0.120396 0.3048)
			(end 0.120396 0.2794)
			(stroke
				(width 0.1)
				(type default)
			)
			(layer "F.Fab")
		)
		(fp_line
			(start 0.120396 0.2794)
			(end -0.12065 0.2794)
			(stroke
				(width 0.1)
				(type default)
			)
			(layer "F.Fab")
		)
		(fp_line
			(start -0.12065 0.3048)
			(end -0.67945 0.3048)
			(stroke
				(width 0.1)
				(type default)
			)
			(layer "F.Fab")
		)
		(fp_line
			(start -0.12065 0.2794)
			(end -0.12065 0.3048)
			(stroke
				(width 0.1)
				(type default)
			)
			(layer "F.Fab")
		)
		(fp_line
			(start -0.12065 -0.2794)
			(end 0.12065 -0.2794)
			(stroke
				(width 0.1)
				(type default)
			)
			(layer "F.Fab")
		)
		(fp_line
			(start -0.12065 -0.305054)
			(end -0.12065 -0.2794)
			(stroke
				(width 0.1)
				(type default)
			)
			(layer "F.Fab")
		)
		(fp_line
			(start -0.67945 0.3048)
			(end -0.67945 -0.305054)
			(stroke
				(width 0.1)
				(type default)
			)
			(layer "F.Fab")
		)
		(fp_line
			(start -0.67945 -0.305054)
			(end -0.12065 -0.305054)
			(stroke
				(width 0.1)
				(type default)
			)
			(layer "F.Fab")
		)
		(pad "1" smd circle
			(at -0.40005 0 180)
			(size 0 0)
			(layers "F.Cu" "F.Mask" "F.Paste")
			(net "P0V8_PEX0_ADDR")
		)
		(pad "2" smd circle
			(at 0.40005 0 180)
			(size 0 0)
			(layers "F.Cu" "F.Mask" "F.Paste")
			(net "GND")
		)
	)
	(footprint ""
		(layer "F.Cu")
		(at 148.26361 -384.566668)
		(property "Reference" "C4082"
			(at 0 0 0)
			(layer "F.SilkS")
			(hide yes)
			(effects
				(font
					(size 1.27 1.27)
				)
			)
		)
		(property "Value" ""
			(at 0 0 0)
			(layer "F.Fab")
			(effects
				(font
					(size 1.27 1.27)
				)
			)
		)
		(duplicate_pad_numbers_are_jumpers no)
		(fp_line
			(start -0.7874 -0.4064)
			(end 0.7874 -0.4064)
			(stroke
				(width 0.1524)
				(type default)
			)
			(layer "F.SilkS")
		)
		(fp_line
			(start -0.7874 0.4064)
			(end -0.7874 -0.4064)
			(stroke
				(width 0.1524)
				(type default)
			)
			(layer "F.SilkS")
		)
		(fp_line
			(start 0.7874 -0.4064)
			(end 0.7874 0.4064)
			(stroke
				(width 0.1524)
				(type default)
			)
			(layer "F.SilkS")
		)
		(fp_line
			(start 0.7874 0.4064)
			(end -0.7874 0.4064)
			(stroke
				(width 0.1524)
				(type default)
			)
			(layer "F.SilkS")
		)
		(fp_line
			(start -0.67945 -0.305054)
			(end -0.12065 -0.305054)
			(stroke
				(width 0.1)
				(type default)
			)
			(layer "F.Fab")
		)
		(fp_line
			(start -0.67945 0.3048)
			(end -0.67945 -0.305054)
			(stroke
				(width 0.1)
				(type default)
			)
			(layer "F.Fab")
		)
		(fp_line
			(start -0.12065 -0.305054)
			(end -0.12065 -0.2794)
			(stroke
				(width 0.1)
				(type default)
			)
			(layer "F.Fab")
		)
		(fp_line
			(start -0.12065 -0.2794)
			(end 0.12065 -0.2794)
			(stroke
				(width 0.1)
				(type default)
			)
			(layer "F.Fab")
		)
		(fp_line
			(start -0.12065 0.2794)
			(end -0.12065 0.3048)
			(stroke
				(width 0.1)
				(type default)
			)
			(layer "F.Fab")
		)
		(fp_line
			(start -0.12065 0.3048)
			(end -0.67945 0.3048)
			(stroke
				(width 0.1)
				(type default)
			)
			(layer "F.Fab")
		)
		(fp_line
			(start 0.120396 0.2794)
			(end -0.12065 0.2794)
			(stroke
				(width 0.1)
				(type default)
			)
			(layer "F.Fab")
		)
		(fp_line
			(start 0.120396 0.3048)
			(end 0.120396 0.2794)
			(stroke
				(width 0.1)
				(type default)
			)
			(layer "F.Fab")
		)
		(fp_line
			(start 0.12065 -0.3048)
			(end 0.67945 -0.3048)
			(stroke
				(width 0.1)
				(type default)
			)
			(layer "F.Fab")
		)
		(fp_line
			(start 0.12065 -0.2794)
			(end 0.12065 -0.3048)
			(stroke
				(width 0.1)
				(type default)
			)
			(layer "F.Fab")
		)
		(fp_line
			(start 0.67945 -0.3048)
			(end 0.67945 0.3048)
			(stroke
				(width 0.1)
				(type default)
			)
			(layer "F.Fab")
		)
		(fp_line
			(start 0.67945 0.3048)
			(end 0.120396 0.3048)
			(stroke
				(width 0.1)
				(type default)
			)
			(layer "F.Fab")
		)
		(pad "1" smd circle
			(at -0.40005 0)
			(size 0 0)
			(layers "F.Cu" "F.Mask" "F.Paste")
			(net "GND")
		)
		(pad "2" smd circle
			(at 0.40005 0)
			(size 0 0)
			(layers "F.Cu" "F.Mask" "F.Paste")
			(net "RST_GPU_FPGA_EROT_N")
		)
	)
)
